# S9S_MB_2U (Grand Teton) — schematic netlist excerpt (pin names and nets, part order shuffled) for the footprints in the layout excerpt that follows; sources: Cadence DE-HDL packaged netlist, KiCad conversion of 03242023_DA0F0TMBIJ0_F0T_Motherboard_J_brd_V01_OCP.brd

C1041  Q_CAP  22UF 4V 20% X6S  pkg C0402  page 74 : A = PVCCIN_CPU0 ; B = GND
PR3792  Q_RES  10 1% EMPTY  pkg 0402LF  page 156 : A = P12V_AUX ; B = P12V_OCP_VCC_1

(kicad_pcb
	(version 20260206)
	(generator "pcbnew")
	(generator_version "10.0")
	(general
		(thickness 1.6)
		(legacy_teardrops no)
	)
	(paper "A4")
	(title_block
		(title "03242023_DA0F0TMBIJ0_F0T_Motherboard_J_brd_V01_OCP.brd")
		(comment 1 "Grand Teton / footprints 1938-1939 of 6105")
	)
	(layers
		(0 "F.Cu" signal "TOP")
		(4 "In1.Cu" signal "GND")
		(6 "In2.Cu" signal "IN1")
		(8 "In3.Cu" signal "GND1")
		(10 "In4.Cu" signal "IN2")
		(12 "In5.Cu" signal "GND2")
		(14 "In6.Cu" signal "IN3")
		(16 "In7.Cu" signal "GND3")
		(18 "In8.Cu" signal "VCC")
		(20 "In9.Cu" signal "VCC1")
		(22 "In10.Cu" signal "GND4")
		(24 "In11.Cu" signal "IN4")
		(26 "In12.Cu" signal "GND5")
		(28 "In13.Cu" signal "IN5")
		(30 "In14.Cu" signal "GND6")
		(32 "In15.Cu" signal "IN6")
		(34 "In16.Cu" signal "GND7")
		(2 "B.Cu" signal "BOTTOM")
		(9 "F.Adhes" user "F.Adhesive")
		(11 "B.Adhes" user "B.Adhesive")
		(13 "F.Paste" user "Package Geometry/Pastemask Top")
		(15 "B.Paste" user "Package Geometry/Pastemask Bottom")
		(5 "F.SilkS" user "Ref Des/Silkscreen Top")
		(7 "B.SilkS" user "Ref Des/Silkscreen Bottom")
		(1 "F.Mask" user "Board Geometry/Soldermask Top")
		(3 "B.Mask" user "Board Geometry/Soldermask Bottom")
		(17 "Dwgs.User" user "User.Drawings")
		(19 "Cmts.User" user "User.Comments")
		(21 "Eco1.User" user "User.Eco1")
		(23 "Eco2.User" user "User.Eco2")
		(25 "Edge.Cuts" user "Board Geometry/Outline")
		(27 "Margin" user)
		(31 "F.CrtYd" user "Package Geometry/Place Bound Top")
		(29 "B.CrtYd" user "Package Geometry/Place Bound Bottom")
		(35 "F.Fab" user "Ref Des/Assembly Top")
		(33 "B.Fab" user "Ref Des/Assembly Bottom")
	)
	(footprint ""
		(layer "F.Cu")
		(at 450.060314 -25.10028 -90)
		(property "Reference" "PR3792"
			(at 0 0 270)
			(layer "F.SilkS")
			(hide yes)
			(effects
				(font
					(size 1.27 1.27)
				)
			)
		)
		(property "Value" ""
			(at 0 0 270)
			(layer "F.Fab")
			(effects
				(font
					(size 1.27 1.27)
				)
			)
		)
		(duplicate_pad_numbers_are_jumpers no)
		(fp_line
			(start -0.7874 0.4064)
			(end -0.7874 -0.4064)
			(stroke
				(width 0.1524)
				(type default)
			)
			(layer "F.SilkS")
		)
		(fp_line
			(start 0.7874 0.4064)
			(end -0.7874 0.4064)
			(stroke
				(width 0.1524)
				(type default)
			)
			(layer "F.SilkS")
		)
		(fp_line
			(start -0.7874 -0.4064)
			(end 0.7874 -0.4064)
			(stroke
				(width 0.1524)
				(type default)
			)
			(layer "F.SilkS")
		)
		(fp_line
			(start 0.7874 -0.4064)
			(end 0.7874 0.4064)
			(stroke
				(width 0.1524)
				(type default)
			)
			(layer "F.SilkS")
		)
		(fp_line
			(start -0.67945 0.3048)
			(end -0.67945 -0.305054)
			(stroke
				(width 0.1)
				(type default)
			)
			(layer "F.Fab")
		)
		(fp_line
			(start -0.12065 0.3048)
			(end -0.67945 0.3048)
			(stroke
				(width 0.1)
				(type default)
			)
			(layer "F.Fab")
		)
		(fp_line
			(start 0.120396 0.3048)
			(end 0.120396 0.2794)
			(stroke
				(width 0.1)
				(type default)
			)
			(layer "F.Fab")
		)
		(fp_line
			(start 0.67945 0.3048)
			(end 0.120396 0.3048)
			(stroke
				(width 0.1)
				(type default)
			)
			(layer "F.Fab")
		)
		(fp_line
			(start -0.12065 0.2794)
			(end -0.12065 0.3048)
			(stroke
				(width 0.1)
				(type default)
			)
			(layer "F.Fab")
		)
		(fp_line
			(start 0.120396 0.2794)
			(end -0.12065 0.2794)
			(stroke
				(width 0.1)
				(type default)
			)
			(layer "F.Fab")
		)
		(fp_line
			(start -0.12065 -0.2794)
			(end 0.12065 -0.2794)
			(stroke
				(width 0.1)
				(type default)
			)
			(layer "F.Fab")
		)
		(fp_line
			(start 0.12065 -0.2794)
			(end 0.12065 -0.3048)
			(stroke
				(width 0.1)
				(type default)
			)
			(layer "F.Fab")
		)
		(fp_line
			(start 0.12065 -0.3048)
			(end 0.67945 -0.3048)
			(stroke
				(width 0.1)
				(type default)
			)
			(layer "F.Fab")
		)
		(fp_line
			(start 0.67945 -0.3048)
			(end 0.67945 0.3048)
			(stroke
				(width 0.1)
				(type default)
			)
			(layer "F.Fab")
		)
		(fp_line
			(start -0.67945 -0.305054)
			(end -0.12065 -0.305054)
			(stroke
				(width 0.1)
				(type default)
			)
			(layer "F.Fab")
		)
		(fp_line
			(start -0.12065 -0.305054)
			(end -0.12065 -0.2794)
			(stroke
				(width 0.1)
				(type default)
			)
			(layer "F.Fab")
		)
		(pad "1" smd circle
			(at -0.40005 0 270)
			(size 0 0)
			(layers "F.Cu" "F.Mask" "F.Paste")
			(net "P12V_AUX")
		)
		(pad "2" smd circle
			(at 0.40005 0 270)
			(size 0 0)
			(layers "F.Cu" "F.Mask" "F.Paste")
			(net "P12V_OCP_VCC_1")
		)
	)
	(footprint ""
		(layer "F.Cu")
		(at 364.50143 -240.276888 90)
		(property "Reference" "C1041"
			(at 0 0 90)
			(layer "F.SilkS")
			(hide yes)
			(effects
				(font
					(size 1.27 1.27)
				)
			)
		)
		(property "Value" ""
			(at 0 0 90)
			(layer "F.Fab")
			(effects
				(font
					(size 1.27 1.27)
				)
			)
		)
		(duplicate_pad_numbers_are_jumpers no)
		(fp_line
			(start 0.7874 -0.4064)
			(end 0.7874 0.4064)
			(stroke
				(width 0.1524)
				(type default)
			)
			(layer "F.SilkS")
		)
		(fp_line
			(start -0.7874 -0.4064)
			(end 0.7874 -0.4064)
			(stroke
				(width 0.1524)
				(type default)
			)
			(layer "F.SilkS")
		)
		(fp_line
			(start 0.7874 0.4064)
			(end -0.7874 0.4064)
			(stroke
				(width 0.1524)
				(type default)
			)
			(layer "F.SilkS")
		)
		(fp_line
			(start -0.7874 0.4064)
			(end -0.7874 -0.4064)
			(stroke
				(width 0.1524)
				(type default)
			)
			(layer "F.SilkS")
		)
		(fp_line
			(start -0.12065 -0.305054)
			(end -0.12065 -0.2794)
			(stroke
				(width 0.1)
				(type default)
			)
			(layer "F.Fab")
		)
		(fp_line
			(start -0.67945 -0.305054)
			(end -0.12065 -0.305054)
			(stroke
				(width 0.1)
				(type default)
			)
			(layer "F.Fab")
		)
		(fp_line
			(start 0.67945 -0.3048)
			(end 0.67945 0.3048)
			(stroke
				(width 0.1)
				(type default)
			)
			(layer "F.Fab")
		)
		(fp_line
			(start 0.12065 -0.3048)
			(end 0.67945 -0.3048)
			(stroke
				(width 0.1)
				(type default)
			)
			(layer "F.Fab")
		)
		(fp_line
			(start 0.12065 -0.2794)
			(end 0.12065 -0.3048)
			(stroke
				(width 0.1)
				(type default)
			)
			(layer "F.Fab")
		)
		(fp_line
			(start -0.12065 -0.2794)
			(end 0.12065 -0.2794)
			(stroke
				(width 0.1)
				(type default)
			)
			(layer "F.Fab")
		)
		(fp_line
			(start 0.120396 0.2794)
			(end -0.12065 0.2794)
			(stroke
				(width 0.1)
				(type default)
			)
			(layer "F.Fab")
		)
		(fp_line
			(start -0.12065 0.2794)
			(end -0.12065 0.3048)
			(stroke
				(width 0.1)
				(type default)
			)
			(layer "F.Fab")
		)
		(fp_line
			(start 0.67945 0.3048)
			(end 0.120396 0.3048)
			(stroke
				(width 0.1)
				(type default)
			)
			(layer "F.Fab")
		)
		(fp_line
			(start 0.120396 0.3048)
			(end 0.120396 0.2794)
			(stroke
				(width 0.1)
				(type default)
			)
			(layer "F.Fab")
		)
		(fp_line
			(start -0.12065 0.3048)
			(end -0.67945 0.3048)
			(stroke
				(width 0.1)
				(type default)
			)
			(layer "F.Fab")
		)
		(fp_line
			(start -0.67945 0.3048)
			(end -0.67945 -0.305054)
			(stroke
				(width 0.1)
				(type default)
			)
			(layer "F.Fab")
		)
		(pad "1" smd circle
			(at -0.40005 0 90)
			(size 0 0)
			(layers "F.Cu" "F.Mask" "F.Paste")
			(net "PVCCIN_CPU0")
		)
		(pad "2" smd circle
			(at 0.40005 0 90)
			(size 0 0)
			(layers "F.Cu" "F.Mask" "F.Paste")
			(net "GND")
		)
	)
)
